FILE_TYPE = CONNECTIVITY;
{Allegro Design Entry HDL 16.6-p007 (v16-6-112F) 10/10/2012}
"PAGE_NUMBER" = 206;
0"NC";
1"PVCCIO_CPU1\g";
2"P3V3_STBY\g";
3"P3V3_STBY\g";
4"GND\g";
5"GND\g";
6"GND\g";
7"GND\g";
8"GND\g";
9"GND\g";
10"PVCCIO_CPU1\g";
11"VR_FET_SW_P12V_STBY_PVCCIN_CPU1\g";
12"GND\g";
13"GND\g";
14"GND\g";
15"GND\g";
16"GND\g";
17"GND\g";
18"VR_PVCCIN_CPU1_VD12";
19"VSENSE_PVSA_CPU1_P";
20"VSENSE_PVCCIN_CPU1_P";
21"ISENSE_PVCCIN_CPU1_PH5_IMON";
22"ISENSE_PVCCIN_CPU1_PH3_IMON";
23"ISENSE_PVCCIN_CPU1_PH2_IMON";
24"ISENSE_PVCCIN_CPU1_PH1_IMON";
25"VR_PVCCIN_CPU1_AIREF3";
26"VR_PVCCIN_CPU1_AIREF2";
27"VR_PVCCIN_CPU1_AIREF1";
28"VSENSE_PVCCIN_CPU1_AVSP";
29"VSENSE_PVCCIN_CPU1_N";
30"ISENSE_PVSA_CPU1_IMON";
31"A_TSENSE_PVSA_CPU1";
32"VR_PVSA_CPU1_BIREF1";
33"VR_PVCCIN_CPU1_XADDR1"VOLTAGE"3.3";
34"VR_PVCCIN_CPU1_XADDR2"VOLTAGE"3.3";
35"FM_PVCCIN_PVCCSA_CPU1_EN_LVC1";
36"VR_PVCCIN_CPU1_VD12";
37"VR_PVCCIN_CPU1_AIREF5";
38"VR_PVCCIN_CPU1_AIREF4";
39"VSENSE_PVSA_CPU1_BVSP";
40"VR_PVCCIN_CPU1_AVINSEN"VOLTAGE"0.8";
41"PVCCIN_PVSA_CPU1_IINSEN"VOLTAGE"+1.5V";
42"A_TSENSE_PVCCIN_CPU1"VOLTAGE"3.6";
43"VSENSE_PVSA_CPU1_N";
44"TP_PVCCIN_CPU1_AIREF6";
45"TP_PVCCIN_CPU1_AISEN6";
46"TP_PVCCIN_CPU1_RESET_N";
47"SVID_VCLK_PVCCIN_CPU1";
48"SVID_CLK0_CPU1_R";
49"VR_PVCCIN_CPU1_VREN"VOLTAGE"3.3";
50"VR_PVCCIN_CPU1_AVINSEN";
51"VR_PVCCIN_CPU1_VDD"VOLTAGE"3.3";
52"IRQ_PVCCIN_CPU1_VRHOT_LVC3_R_N";
53"TP_PVCCIN_CPU1_FAULT1_20";
54"TP_PVCCIN_CPU1_GP1";
55"SVID_VALERT_VCCIN_CPU1";
56"SVID_VDIO_PVCCIN_CPU1";
57"TP_PVCCIN_CPU1_APWM6";
58"SMB_VR_SCL_R1";
59"SMB_VR_SDA_R1";
60"PWRGD_PVSA_CPU1_R";
61"PU_VR_PVCCIN_CPU1_FLT1_SMBALT_N_IMON";
62"PU_VR_PVCCIN_CPU1_IMON";
63"IRQ_PVCCIN_CPU1_VRHOT_LVC3_N";
64"VR_PVCCIN_CPU1_PWM5";
65"VR_PVCCIN_CPU1_PWM3"VOLTAGE"3.6";
66"VR_PVCCIN_CPU1_PWM4"VOLTAGE"3.6";
67"VR_PVCCIN_CPU1_PWM1"VOLTAGE"3.6";
68"VR_PVCCIN_CPU1_PWM2"VOLTAGE"3.6";
69"VR_PVSA_CPU1_PWM"VOLTAGE"3.6";
70"PWRGD_PVSA_CPU1";
71"VR_PVCCIN_CPU1_VD12";
72"FM_PVCCIN_CPU1_PWR_IN_ALERT_N";
73"SMB_VR_STBY_LVC3_SCL";
74"SMB_VR_STBY_LVC3_SDA";
75"VR_PVCCIN_CPU1_VD12";
76"SVID_ALERT0_CPU1_R_N";
77"SVID_DIO0_CPU1_R";
78"VR_VRRDY_PVCCIN_CPU1";
79"PWRGD_PVCCIN_CPU1";
80"ISENSE_PVCCIN_CPU1_PH4_IMON";
%"PVCCIO_CPU1"
"1","(-1375,4150)","0","mstr_symbols","I1";
;
HDL_POWER"PVCCIO_CPU1"
BODY_TYPE"PLUMBING"
VOLTAGE"1.1V"
CDS_LIB"mstr_symbols";
"G\NAC"1;
%"P3V3_STBY"
"1","(-4350,4600)","0","mstr_symbols","I103";
;
HDL_POWER"P3V3_STBY"
BODY_TYPE"PLUMBING"
SIZE"1B"
CDS_LIB"mstr_symbols"
VOLTAGE"3.3V";
"G\NAC"2;
%"P3V3_STBY"
"1","(-3075,4575)","0","mstr_symbols","I104";
;
HDL_POWER"P3V3_STBY"
BODY_TYPE"PLUMBING"
SIZE"1B"
CDS_LIB"mstr_symbols"
VOLTAGE"3.3V";
"G\NAC"3;
%"RES"
"2","(-4500,925)","0","mstr_discrete","I111";
;
CDS_SEC"1"
SEC_TYPE"0402"
SEC"1"
CDS_LOCATION"R9N7"
ROOM"PVCCIN_CPU1_VR"
CDS_LIB"mstr_discrete"
LOCATION"R9N7"
VALUE"3.16K"
PART_NUMBER"G21796-043"
PACK_TYPE"0402"
MATERIAL"CHIP"
WATTAGE"1/16W"
TOLERANCE"1%";
"A"
$PN"1"34;
"B"
$PN"2"13;
%"RES"
"2","(-4825,925)","0","mstr_discrete","I112";
;
CDS_SEC"1"
SEC_TYPE"0402"
SEC"1"
CDS_LOCATION"R9N8"
ROOM"PVCCIN_CPU1_VR"
CDS_LIB"mstr_discrete"
LOCATION"R9N8"
VALUE"4.02K"
PART_NUMBER"G21796-082"
WATTAGE"1/16W"
MATERIAL"CHIP"
TOLERANCE"1%"
PACK_TYPE"0402";
"A"
$PN"1"33;
"B"
$PN"2"14;
%"RES"
"1","(-1200,3375)","0","mstr_discrete","I113";
;
CDS_SEC"1"
SEC_TYPE"0402"
SEC"1"
ROOM"PVCCIN_CPU1_VR"
CDS_LOCATION"R1C30"
CDS_LIB"mstr_discrete"
PACK_TYPE"0402"
PART_NUMBER"G21796-250"
LOCATION"R1C30"
TOLERANCE"1.0%"
MATERIAL"CHIP"
VALUE"22.1"
WATTAGE"1/16W";
"B"
$PN"2"79;
"A"
$PN"1"78;
%"CAP"
"1","(-1450,2150)","0","mstr_discrete","I114";
;
CDS_SEC"1"
ROOM"PVCCIN_CPU1_VR"
SEC"1"
SEC_TYPE"0402LF"
CDS_LOCATION"C1C23"
CDS_LIB"mstr_discrete"
LOCATION"C1C23"
VALUE"1000PF"
MATERIAL"X7R"
VOLTAGE"50V"
TOLERANCE"10%"
PACK_TYPE"0402LF"
PART_NUMBER"A36096-046";
"A"
$PN"1"78;
"B"
$PN"2"4;
%"GND"
"1","(-1450,1925)","0","mstr_symbols","I115";
;
HDL_POWER"GND"
BODY_TYPE"PLUMBING"
ROOM"PVCCIN_CPU1_VR"
CDS_LIB"mstr_symbols"
SIZE"1B"
VOLTAGE"0";
"A\NAC"4;
%"RES"
"1","(-2175,2725)","0","mstr_discrete","I116";
;
CDS_SEC"1"
SEC_TYPE"0402"
SEC"1"
CDS_LIB"mstr_discrete"
CDS_LOCATION"R1D1"
PACK_TYPE"0402"
PART_NUMBER"G21796-074"
MATERIAL"CHIP"
TOLERANCE"1%"
LOCATION"R1D1"
VALUE"33.2"
WATTAGE"1/16W";
"B"
$PN"2"70;
"A"
$PN"1"60;
%"RES"
"1","(-2425,3025)","0","mstr_discrete","I117";
;
CDS_SEC"1"
CDS_LOCATION"R9P3"
SEC"1"
SEC_TYPE"0402"
CDS_LIB"mstr_discrete"
PART_NUMBER"G21796-074"
LOCATION"R9P3"
PACK_TYPE"0402"
TOLERANCE"1%"
MATERIAL"CHIP"
VALUE"33.2"
WATTAGE"1/16W";
"B"
$PN"2"63;
"A"
$PN"1"52;
%"RES"
"1","(-5200,2275)","0","mstr_discrete","I119";
;
CDS_SEC"1"
ROOM"PVCCIN_CPU0_VR"
CDS_LOCATION"R9N16"
SEC"1"
SEC_TYPE"0402"
CDS_LIB"mstr_discrete"
LOCATION"R9N16"
PART_NUMBER"G21497-005"
PACK_TYPE"0402"
MATERIAL"CHIP"
WATTAGE"1/16W"
TOLERANCE"5%"
VALUE"0.0";
"B"
$PN"2"49;
"A"
$PN"1"35;
%"RES"
"2","(-4650,4400)","0","mstr_discrete","I120";
;
CDS_SEC"1"
BOM_COST"SM_CONTROLLER"
SEC_TYPE"0402"
SEC"1"
ROOM"BMC"
CDS_LOCATION"R9N14"
CDS_LIB"mstr_discrete"
LOCATION"R9N14"
VALUE"1.00K"
TOLERANCE"1%"
PART_NUMBER"G21796-026"
PACK_TYPE"0402"
MATERIAL"CHIP"
WATTAGE"1/16W";
"A"
$PN"1"10;
"B"
$PN"2"49;
%"RES"
"2","(-6950,3525)","0","mstr_discrete","I122";
;
CDS_SEC"1"
SEC"1"
CDS_LOCATION"R9N15"
SEC_TYPE"0402"
ROOM"PVCCIN_CPU0_VR"
CDS_LIB"mstr_discrete"
LOCATION"R9N15"
VALUE"0.0"
PACK_TYPE"0402"
WATTAGE"1/16W"
MATERIAL"CHIP"
TOLERANCE"5%"
PART_NUMBER"G21497-005";
"A"
$PN"1"36;
"B"
$PN"2"27;
%"RES"
"2","(-6550,3525)","0","mstr_discrete","I123";
;
CDS_SEC"1"
SEC"1"
CDS_LOCATION"R9N17"
SEC_TYPE"0402"
ROOM"PVCCIN_CPU0_VR"
CDS_LIB"mstr_discrete"
LOCATION"R9N17"
VALUE"0.0"
MATERIAL"CHIP"
WATTAGE"1/16W"
TOLERANCE"5%"
PART_NUMBER"G21497-005"
PACK_TYPE"0402";
"A"
$PN"1"36;
"B"
$PN"2"26;
%"RES"
"2","(-6150,3550)","0","mstr_discrete","I124";
;
CDS_SEC"1"
SEC"1"
SEC_TYPE"0402"
CDS_LOCATION"R9N12"
ROOM"PVCCIN_CPU0_VR"
CDS_LIB"mstr_discrete"
LOCATION"R9N12"
VALUE"0.0"
TOLERANCE"5%"
WATTAGE"1/16W"
MATERIAL"CHIP"
PART_NUMBER"G21497-005"
PACK_TYPE"0402";
"A"
$PN"1"36;
"B"
$PN"2"25;
%"RES"
"2","(-5725,3550)","0","mstr_discrete","I125";
;
CDS_SEC"1"
SEC_TYPE"0402"
SEC"1"
CDS_LOCATION"R9N10"
ROOM"PVCCIN_CPU0_VR"
CDS_LIB"mstr_discrete"
LOCATION"R9N10"
VALUE"0.0"
TOLERANCE"5%"
MATERIAL"CHIP"
WATTAGE"1/16W"
PACK_TYPE"0402"
PART_NUMBER"G21497-005";
"A"
$PN"1"36;
"B"
$PN"2"38;
%"RES"
"2","(-5275,3550)","0","mstr_discrete","I126";
;
CDS_SEC"1"
SEC_TYPE"0402"
SEC"1"
CDS_LOCATION"R9N9"
ROOM"PVCCIN_CPU0_VR"
CDS_LIB"mstr_discrete"
LOCATION"R9N9"
MATERIAL"CHIP"
WATTAGE"1/16W"
VALUE"0.0"
PACK_TYPE"0402"
TOLERANCE"5%"
PART_NUMBER"G21497-005";
"A"
$PN"1"36;
"B"
$PN"2"37;
%"RES"
"1","(-6875,1350)","0","mstr_discrete","I128";
;
CDS_SEC"1"
SEC"1"
SEC_TYPE"0402"
CDS_LIB"mstr_discrete"
ROOM"PVCCIN_CPU0_VR"
CDS_LOCATION"R9N5"
MATERIAL"CHIP"
PACK_TYPE"0402"
LOCATION"R9N5"
PART_NUMBER"G21497-005"
TOLERANCE"5%"
WATTAGE"1/16W"
VALUE"0.0";
"B"
$PN"2"32;
"A"
$PN"1"18;
%"PXE1610B"
"1","(-3825,2625)","0","mstr_controller","I130";
;
CDS_SEC"1"
CDS_LIB"mstr_controller"
CDS_LMAN_SYM_OUTLINE"-400,900,400,-900"
PACK_TYPE"QFN"
SEC_TYPE"QFN"
SEC"1"
CDS_LOCATION"EU1C2"
LOCATION"EU1C2"
PART_NUMBER"H79206-001"
MATERIAL"IC";
"MP4"
$PN"40"53;
"MP3"
$PN"39"62;
"MP2"
$PN"20"61;
"MP1"
$PN"16"54;
"MP0"
$PN"15"60;
"AVREN"
$PN"12"49;
"AVRRDY"
$PN"11"78;
"VD12"
$PN"48"71;
"IINSEN"
$PN"46"41;
"VINSEN"
$PN"45"40;
"BVREF"
$PN"36"43;
"BVSEN"
$PN"35"39;
"AVREF"
$PN"22"29;
"AVSEN"
$PN"21"28;
"VALRT_N \B"
$PN"19"55;
"PINALRT_N \B"
$PN"14"72;
"VRHOT_N \B"
$PN"13"52;
"BIREF1"
$PN"37"32;
"BISEN1"
$PN"38"30;
"BTSEN"
$PN"42"31;
"VDD"
$PN"47"51;
"AIREF1"
$PN"23"27;
"AISEN1"
$PN"24"24;
"ATSEN"
$PN"43"42;
"AIREF2"
$PN"25"26;
"AISEN2"
$PN"26"23;
"XADDR2"
$PN"41"34;
"AIREF3"
$PN"27"25;
"AISEN3"
$PN"28"22;
"XADDR1"
$PN"44"33;
"AIREF4"
$PN"29"38;
"AISEN4"
$PN"30"80;
"AIREF5"
$PN"31"37;
"AISEN5"
$PN"32"21;
"AIREF6"
$PN"33"44;
"AISEN6"
$PN"34"45;
"RESET_N \B"
$PN"10"46;
"VDIO"
$PN"18"56;
"VCLK"
$PN"17"47;
"SCL"
$PN"9"58;
"SDA"
$PN"8"59;
"APWM6"
$PN"2"57;
"APWM5"
$PN"3"64;
"APWM4"
$PN"4"66;
"APWM3"
$PN"5"65;
"APWM2"
$PN"6"68;
"APWM1"
$PN"7"67;
"BPWM1"
$PN"1"69;
"THPAD"
$PN"49"9;
%"RES"
"1","(-2000,1775)","0","mstr_discrete","I27";
;
CDS_SEC"1"
CDS_LIB"mstr_discrete"
ROOM"PVCCIN_CPU1_VR"
CDS_LOCATION"R1C23"
SEC"1"
SEC_TYPE"0402"
PACK_TYPE"0402"
MATERIAL"CHIP"
LOCATION"R1C23"
PART_NUMBER"G21497-005"
TOLERANCE"5%"
WATTAGE"1/16W"
VALUE"0.0";
"B"
$PN"2"74;
"A"
$PN"1"59;
%"RES"
"1","(-2000,1525)","0","mstr_discrete","I28";
;
CDS_SEC"1"
CDS_LIB"mstr_discrete"
SEC_TYPE"0402"
SEC"1"
CDS_LOCATION"R1C25"
ROOM"PVCCIN_CPU1_VR"
MATERIAL"CHIP"
PACK_TYPE"0402"
LOCATION"R1C25"
PART_NUMBER"G21497-005"
TOLERANCE"5%"
WATTAGE"1/16W"
VALUE"0.0";
"B"
$PN"2"73;
"A"
$PN"1"58;
%"CAP_A"
"1","(-1575,1000)","0","dev_discrete","I29";
;
ROOM"PVCCIN_CPU1_VR"
$SEC"1"
CDS_SEC"1"
CDS_LOCATION"C1C13"
CDS_LIB"dev_discrete"
VALUE"1.0UF"
LOCATION"C1C13"
VOLTAGE"6.3V"
PART_NUMBER"D97712-004"
TOLERANCE"10%"
PACK_TYPE"0402V"
MATERIAL"X6S";
"B"
$PN"2"5;
"A"
$PN"1"75;
%"GND"
"1","(-1575,675)","0","mstr_symbols","I30";
;
HDL_POWER"GND"
BODY_TYPE"PLUMBING"
SIZE"1B"
CDS_LIB"mstr_symbols"
VOLTAGE"0"
ROOM"PVCCIN_CPU1_VR";
"A\NAC"5;
%"CAP_A"
"1","(-1975,1000)","0","dev_discrete","I31";
;
ROOM"PVCCIN_CPU1_VR"
CDS_LOCATION"C1C14"
CDS_SEC"1"
SEC_TYPE"0402V"
SEC"1"
CDS_LIB"dev_discrete"
VALUE"0.1UF"
LOCATION"C1C14"
VOLTAGE"16V"
PART_NUMBER"A36096-030"
PACK_TYPE"0402V"
TOLERANCE"10%"
MATERIAL"X7R";
"B"
$PN"2"6;
"A"
$PN"1"75;
%"GND"
"1","(-1975,800)","0","mstr_symbols","I32";
;
HDL_POWER"GND"
BODY_TYPE"PLUMBING"
CDS_LIB"mstr_symbols"
VOLTAGE"0"
SIZE"1B"
ROOM"PVCCIN_CPU1_VR";
"A\NAC"6;
%"RES"
"2","(-2375,4125)","0","mstr_discrete","I33";
;
CDS_SEC"1"
CDS_LOCATION"R1D53"
SEC_TYPE"0402"
SEC"1"
CDS_LIB"mstr_discrete"
ROOM"PVCCIN_CPU1_VR"
LOCATION"R1D53"
VALUE"2.26K"
TOLERANCE"1.0%"
WATTAGE"1/16W"
MATERIAL"EMPTY"
PART_NUMBER"G21796-311"
PACK_TYPE"0402";
"A"
$PN"1"3;
"B"
$PN"2"61;
%"RES"
"2","(-2225,3750)","0","mstr_discrete","I34";
;
CDS_SEC"1"
SEC_TYPE"0402"
SEC"1"
CDS_LOCATION"R1C18"
ROOM"PVCCIN_CPU1_VR"
CDS_LIB"mstr_discrete"
MATERIAL"EMPTY"
LOCATION"R1C18"
PART_NUMBER"G21796-311"
VALUE"2.26K"
WATTAGE"1/16W"
TOLERANCE"1.0%"
PACK_TYPE"0402";
"A"
$PN"1"3;
"B"
$PN"2"62;
%"RES"
"2","(-2725,3925)","0","mstr_discrete","I35";
;
CDS_SEC"1"
SEC_TYPE"0402"
SEC"1"
ROOM"PVCCIN_CPU1_VR"
CDS_LOCATION"R1C28"
CDS_LIB"mstr_discrete"
LOCATION"R1C28"
PART_NUMBER"G21796-026"
VALUE"1.00K"
WATTAGE"1/16W"
MATERIAL"CHIP"
TOLERANCE"1%"
PACK_TYPE"0402";
"A"
$PN"1"3;
"B"
$PN"2"78;
%"RES"
"2","(-2875,3925)","2","mstr_discrete","I36";
;
CDS_SEC"1"
SEC_TYPE"0402"
SEC"1"
ROOM"PVCCIN_CPU1_VR"
CDS_LIB"mstr_discrete"
CDS_LOCATION"R1D8"
MATERIAL"CHIP"
TOLERANCE"1%"
VALUE"1.00K"
LOCATION"R1D8"
WATTAGE"1/16W"
PACK_TYPE"0402"
PART_NUMBER"G21796-026";
"A"
$PN"1"3;
"B"
$PN"2"60;
%"RES"
"1","(-2125,2925)","0","mstr_discrete","I37";
;
CDS_SEC"1"
SEC"1"
SEC_TYPE"0402"
ROOM"PVCCIN_CPU1_VR"
CDS_LOCATION"R1D3"
CDS_LIB"mstr_discrete"
MATERIAL"CHIP"
PACK_TYPE"0402"
LOCATION"R1D3"
TOLERANCE"5%"
VALUE"0.0"
WATTAGE"1/16W"
PART_NUMBER"G21497-005";
"B"
$PN"2"76;
"A"
$PN"1"55;
%"RES"
"1","(-2500,2775)","0","mstr_discrete","I38";
;
CDS_SEC"1"
ROOM"PVCCIN_CPU1_VR"
CDS_LOCATION"R1D2"
SEC"1"
SEC_TYPE"0402"
CDS_LIB"mstr_discrete"
LOCATION"R1D2"
PACK_TYPE"0402"
MATERIAL"CHIP"
PART_NUMBER"G21497-005"
TOLERANCE"5%"
WATTAGE"1/16W"
VALUE"0.0";
"B"
$PN"2"77;
"A"
$PN"1"56;
%"RES"
"2","(-1375,3750)","0","mstr_discrete","I4";
;
CDS_SEC"1"
SEC_TYPE"0402"
SEC"1"
CDS_LOCATION"R9P1"
ROOM"PVCCIN_CPU1_VR"
CDS_LIB"mstr_discrete"
VALUE"100.0"
TOLERANCE"1%"
MATERIAL"CHIP"
PART_NUMBER"G21796-017"
LOCATION"R9P1"
WATTAGE"1/16W"
PACK_TYPE"0402";
"A"
$PN"1"1;
"B"
$PN"2"77;
%"GND"
"1","(-3650,3725)","0","mstr_symbols","I40";
;
HDL_POWER"GND"
BODY_TYPE"PLUMBING"
SIZE"1B"
VOLTAGE"0"
CDS_LIB"mstr_symbols"
ROOM"PVCCIN_CPU1_VR";
"A\NAC"7;
%"CAP_A"
"1","(-3650,3925)","0","dev_discrete","I41";
;
CDS_SEC"1"
$SEC"1"
ROOM"PVCCIN_CPU1_VR"
CDS_LOCATION"C1C7"
CDS_LIB"dev_discrete"
LOCATION"C1C7"
PART_NUMBER"D97712-004"
VALUE"1.0UF"
TOLERANCE"10%"
PACK_TYPE"0402V"
VOLTAGE"6.3V"
MATERIAL"X6S";
"B"
$PN"2"7;
"A"
$PN"1"51;
%"CAP_A"
"1","(-4050,3925)","0","dev_discrete","I42";
;
SEC_TYPE"0402V"
SEC"1"
ROOM"PVCCIN_CPU1_VR"
CDS_SEC"1"
CDS_LOCATION"C1C9"
CDS_LIB"dev_discrete"
PART_NUMBER"A36096-030"
VOLTAGE"16V"
TOLERANCE"10%"
VALUE"0.1UF"
LOCATION"C1C9"
MATERIAL"X7R"
PACK_TYPE"0402V";
"B"
$PN"2"8;
"A"
$PN"1"51;
%"GND"
"1","(-4050,3725)","0","mstr_symbols","I43";
;
HDL_POWER"GND"
BODY_TYPE"PLUMBING"
VOLTAGE"0"
CDS_LIB"mstr_symbols"
SIZE"1B"
ROOM"PVCCIN_CPU1_VR";
"A\NAC"8;
%"GND"
"1","(-3175,1550)","0","mstr_symbols","I44";
;
HDL_POWER"GND"
BODY_TYPE"PLUMBING"
CDS_LIB"mstr_symbols"
VOLTAGE"0"
SIZE"1B"
ROOM"PVCCIN_CPU1_VR";
"A\NAC"9;
%"RES"
"2","(-4350,4275)","0","mstr_discrete","I46";
;
CDS_SEC"1"
ROOM"PVCCIN_CPU1_VR"
CDS_LOCATION"R1C14"
SEC"1"
SEC_TYPE"0402"
CDS_LIB"mstr_discrete"
PART_NUMBER"G21497-005"
LOCATION"R1C14"
VALUE"0.0"
TOLERANCE"5%"
PACK_TYPE"0402"
MATERIAL"CHIP"
WATTAGE"1/16W";
"A"
$PN"1"2;
"B"
$PN"2"51;
%"PVCCIO_CPU1"
"1","(-5225,4875)","0","mstr_symbols","I47";
;
HDL_POWER"PVCCIO_CPU1"
BODY_TYPE"PLUMBING"
CDS_LIB"mstr_symbols"
VOLTAGE"1.1V";
"G\NAC"10;
%"VCC_CORE"
"1","(-6150,4875)","0","mstr_symbols","I48";
;
VOLTAGE"12"
CDS_LIB"mstr_symbols"
HDL_POWER"VR_FET_SW_P12V_STBY_PVCCIN_CPU1";
"A"
VOLTAGE"+3.3V"11;
%"RES"
"2","(-6150,4575)","0","mstr_discrete","I49";
;
CDS_SEC"1"
SEC_TYPE"0402"
SEC"1"
CDS_LOCATION"R1C13"
ROOM"PVCCIN_CPU1_VR"
CDS_LIB"mstr_discrete"
LOCATION"R1C13"
VALUE"100.0K"
TOLERANCE"1%"
PART_NUMBER"G21796-160"
PACK_TYPE"0402"
MATERIAL"CHIP"
WATTAGE"1/16W";
"A"
$PN"1"11;
"B"
$PN"2"50;
%"RES"
"2","(-5650,4450)","0","mstr_discrete","I53";
;
CDS_SEC"1"
SEC"1"
SEC_TYPE"0402"
ROOM"PVCCIN_CPU1_VR"
CDS_LOCATION"R9P2"
CDS_LIB"mstr_discrete"
TOLERANCE"1%"
VALUE"49.9"
PART_NUMBER"G21796-047"
LOCATION"R9P2"
PACK_TYPE"0402"
MATERIAL"CHIP"
WATTAGE"1/16W";
"A"
$PN"1"10;
"B"
$PN"2"48;
%"RES"
"1","(-5375,3900)","0","mstr_discrete","I54";
;
ROOM"PVCCIN_CPU1_VR"
$SEC"1"
CDS_SEC"1"
CDS_LOCATION"R1D9"
CDS_LIB"mstr_discrete"
LOCATION"R1D9"
MATERIAL"CHIP"
PACK_TYPE"0402"
TOLERANCE"1%"
PART_NUMBER"G21796-009"
VALUE"150.0"
WATTAGE"1/16W";
"B"
$PN"2"47;
"A"
$PN"1"48;
%"RES"
"2","(-6150,4225)","0","mstr_discrete","I56";
;
CDS_SEC"1"
SEC"1"
CDS_LOCATION"R1C16"
ROOM"PVCCIN_CPU1_VR"
SEC_TYPE"0402"
CDS_LIB"mstr_discrete"
PART_NUMBER"G21796-003"
LOCATION"R1C16"
VALUE"1.5K"
TOLERANCE"1%"
WATTAGE"1/16W"
MATERIAL"CHIP"
PACK_TYPE"0402";
"A"
$PN"1"50;
"B"
$PN"2"12;
%"GND"
"1","(-6150,3975)","0","mstr_symbols","I57";
;
HDL_POWER"GND"
BODY_TYPE"PLUMBING"
ROOM"PVCCIN_CPU1_VR"
SIZE"1B"
CDS_LIB"mstr_symbols"
VOLTAGE"0";
"A\NAC"12;
%"RES"
"2","(-3075,4000)","2","mstr_discrete","I6";
;
CDS_SEC"1"
ROOM"PVCCIN_CPU1_VR"
CDS_LOCATION"R1D6"
SEC"1"
SEC_TYPE"0402"
CDS_LIB"mstr_discrete"
LOCATION"R1D6"
VALUE"1.00K"
PART_NUMBER"G21796-026"
TOLERANCE"1%"
PACK_TYPE"0402"
MATERIAL"CHIP"
WATTAGE"1/16W";
"A"
$PN"1"3;
"B"
$PN"2"52;
%"GND"
"1","(-4500,575)","0","mstr_symbols","I65";
;
HDL_POWER"GND"
BODY_TYPE"PLUMBING"
VOLTAGE"0"
CDS_LIB"mstr_symbols"
SIZE"1B"
ROOM"PVCCIN_CPU1_VR";
"A\NAC"13;
%"GND"
"1","(-4825,525)","0","mstr_symbols","I67";
;
HDL_POWER"GND"
BODY_TYPE"PLUMBING"
VOLTAGE"0"
CDS_LIB"mstr_symbols"
SIZE"1B"
ROOM"PVCCIN_CPU1_VR";
"A\NAC"14;
%"CAP"
"1","(-5650,2075)","0","mstr_discrete","I68";
;
CDS_SEC"1"
SEC"1"
NO_XNET_CONNECTION"1"
SEC_TYPE"0402LF"
CDS_LIB"mstr_discrete"
CDS_LOCATION"C1C16"
ROOM"PVCCIN_CPU1_VR"
LOCATION"C1C16"
PART_NUMBER"A36096-050"
VALUE"220PF"
TOLERANCE"10%"
PACK_TYPE"0402LF"
MATERIAL"X7R"
VOLTAGE"50V";
"A"
$PN"1"39;
"B"
$PN"2"43;
%"CAP"
"1","(-5925,1275)","0","mstr_discrete","I69";
;
CDS_SEC"1"
SEC"1"
SEC_TYPE"0402LF"
CDS_LOCATION"C1C10"
ROOM"PVCCIN_CPU1_VR"
CDS_LIB"mstr_discrete"
PART_NUMBER"A36096-050"
TOLERANCE"10%"
PACK_TYPE"0402LF"
VALUE"220PF"
LOCATION"C1C10"
MATERIAL"X7R"
VOLTAGE"50V";
"A"
$PN"1"42;
"B"
$PN"2"15;
%"RES"
"2","(-2050,4100)","0","mstr_discrete","I7";
;
CDS_SEC"1"
SEC_TYPE"0402"
SEC"1"
CDS_LOCATION"R1D7"
CDS_LIB"mstr_discrete"
ROOM"PVCCIN_CPU1_VR"
LOCATION"R1D7"
VALUE"2.26K"
TOLERANCE"1.0%"
WATTAGE"1/16W"
PART_NUMBER"G21796-311"
PACK_TYPE"0402"
MATERIAL"CHIP";
"A"
$PN"1"3;
"B"
$PN"2"72;
%"GND"
"1","(-5925,575)","0","mstr_symbols","I70";
;
HDL_POWER"GND"
BODY_TYPE"PLUMBING"
SIZE"1B"
CDS_LIB"mstr_symbols"
VOLTAGE"0"
ROOM"PVCCIN_CPU1_VR";
"A\NAC"15;
%"CAP"
"1","(-6150,1000)","2","mstr_discrete","I71";
;
CDS_SEC"1"
ROOM"PVCCIN_CPU1_VR"
CDS_LOCATION"C1C11"
SEC"1"
SEC_TYPE"0402LF"
CDS_LIB"mstr_discrete"
TOLERANCE"10%"
VALUE"220PF"
LOCATION"C1C11"
VOLTAGE"50V"
MATERIAL"X7R"
PACK_TYPE"0402LF"
PART_NUMBER"A36096-050";
"A"
$PN"1"31;
"B"
$PN"2"16;
%"GND"
"1","(-6150,575)","0","mstr_symbols","I72";
;
HDL_POWER"GND"
BODY_TYPE"PLUMBING"
SIZE"1B"
VOLTAGE"0"
CDS_LIB"mstr_symbols"
ROOM"PVCCIN_CPU1_VR";
"A\NAC"16;
%"CAP"
"1","(-6425,4200)","2","mstr_discrete","I73";
;
CDS_SEC"1"
SEC_TYPE"0402LF"
SEC"1"
ROOM"PVCCIN_CPU1_VR"
CDS_LOCATION"C1C8"
CDS_LIB"mstr_discrete"
VOLTAGE"50V"
TOLERANCE"10%"
VALUE"1000PF"
LOCATION"C1C8"
MATERIAL"X7R"
PACK_TYPE"0402LF"
PART_NUMBER"A36096-046";
"A"
$PN"1"50;
"B"
$PN"2"17;
%"GND"
"1","(-6425,3975)","0","mstr_symbols","I74";
;
HDL_POWER"GND"
BODY_TYPE"PLUMBING"
ROOM"PVCCIN_CPU1_VR"
SIZE"1B"
CDS_LIB"mstr_symbols"
VOLTAGE"0";
"A\NAC"17;
%"RES"
"1","(-6350,2075)","0","mstr_discrete","I77";
;
CDS_SEC"1"
CDS_LIB"mstr_discrete"
SEC_TYPE"0402"
SEC"1"
CDS_LOCATION"R1C21"
ROOM"PVCCIN_CPU1_VR"
PART_NUMBER"G21796-066"
LOCATION"R1C21"
NO_XNET_CONNECTION"1"
PACK_TYPE"0402"
WATTAGE"1/16W"
MATERIAL"CHIP"
TOLERANCE"1%"
VALUE"10.0";
"B"
$PN"2"39;
"A"
$PN"1"19;
%"CAP"
"1","(-6550,2375)","0","mstr_discrete","I78";
;
CDS_SEC"1"
SEC_TYPE"0402LF"
SEC"1"
ROOM"PVCCIN_CPU1_VR"
CDS_LOCATION"C1D1"
CDS_LIB"mstr_discrete"
NO_XNET_CONNECTION"1"
MATERIAL"X7R"
TOLERANCE"10%"
LOCATION"C1D1"
PART_NUMBER"A36096-050"
VALUE"220PF"
PACK_TYPE"0402LF"
VOLTAGE"50V";
"A"
$PN"1"28;
"B"
$PN"2"29;
%"RES"
"1","(-6775,2575)","0","mstr_discrete","I79";
;
CDS_SEC"1"
SEC_TYPE"0402"
CDS_LIB"mstr_discrete"
ROOM"PVCCIN_CPU1_VR"
CDS_LOCATION"R1D4"
SEC"1"
PART_NUMBER"G21796-066"
NO_XNET_CONNECTION"1"
LOCATION"R1D4"
WATTAGE"1/16W"
VALUE"10.0"
TOLERANCE"1%"
PACK_TYPE"0402"
MATERIAL"CHIP";
"B"
$PN"2"28;
"A"
$PN"1"20;
END.
